# BASEBOARD_FAB2 (Tioga Pass) — schematic netlist excerpt (pin names and nets, part order shuffled) for the footprints in the layout excerpt that follows; sources: Cadence DE-HDL packaged netlist, KiCad conversion of Wiwynn_Tioga_Pass_MB.brd

C7B20  CAP_A  22.0UF 4V 20% X6S  pkg 0603V  page 131 : A = P1V05_PCH_STBY ; B = GND
R1G5  RES  10.0 1% CHIP  pkg 0402  page 223 : A = VSENSE_PVDDQ_GHJ_P ; B = VR_PVDDQ_GHJ_AVSP
C7F1  CAP_A  0.01UF 25V 10% X7R  pkg 0402V  page 153 : A = P3V3_STBY ; B = GND

(kicad_pcb
	(version 20260206)
	(generator "pcbnew")
	(generator_version "10.0")
	(general
		(thickness 1.6)
		(legacy_teardrops no)
	)
	(paper "A4")
	(title_block
		(title "Wiwynn_Tioga_Pass_MB.brd")
		(comment 1 "Tioga Pass / footprints 1794-1796 of 4770")
	)
	(layers
		(0 "F.Cu" signal "TOP")
		(4 "In1.Cu" signal "L2GND")
		(6 "In2.Cu" signal "L3")
		(8 "In3.Cu" signal "L4GND")
		(10 "In4.Cu" signal "L5")
		(12 "In5.Cu" signal "L6GND")
		(14 "In6.Cu" signal "L7VCC")
		(16 "In7.Cu" signal "L8VCC")
		(18 "In8.Cu" signal "L9GND")
		(20 "In9.Cu" signal "L10")
		(22 "In10.Cu" signal "L11GND")
		(24 "In11.Cu" signal "L12")
		(26 "In12.Cu" signal "L13GND")
		(2 "B.Cu" signal "BOTTOM")
		(9 "F.Adhes" user "F.Adhesive")
		(11 "B.Adhes" user "B.Adhesive")
		(13 "F.Paste" user "Package Geometry/Pastemask Top")
		(15 "B.Paste" user "Package Geometry/Pastemask Bottom")
		(5 "F.SilkS" user "Ref Des/Silkscreen Top")
		(7 "B.SilkS" user "Ref Des/Silkscreen Bottom")
		(1 "F.Mask" user "Board Geometry/Soldermask Top")
		(3 "B.Mask" user "Board Geometry/Soldermask Bottom")
		(17 "Dwgs.User" user "User.Drawings")
		(19 "Cmts.User" user "User.Comments")
		(21 "Eco1.User" user "User.Eco1")
		(23 "Eco2.User" user "User.Eco2")
		(25 "Edge.Cuts" user "Board Geometry/Outline")
		(27 "Margin" user)
		(31 "F.CrtYd" user "Package Geometry/Place Bound Top")
		(29 "B.CrtYd" user "Package Geometry/Place Bound Bottom")
		(35 "F.Fab" user "Ref Des/Assembly Top")
		(33 "B.Fab" user "Ref Des/Assembly Bottom")
	)
	(footprint ""
		(layer "F.Cu")
		(at 7.137146 -4.548886 90)
		(property "Reference" "R1G5"
			(at 0 0 90)
			(layer "F.SilkS")
			(hide yes)
			(effects
				(font
					(size 1.27 1.27)
				)
			)
		)
		(property "Value" ""
			(at 0 0 90)
			(layer "F.Fab")
			(effects
				(font
					(size 1.27 1.27)
				)
			)
		)
		(duplicate_pad_numbers_are_jumpers no)
		(fp_rect
			(start 0.2794 -0.1016)
			(end -0.2794 0.9906)
			(stroke
				(width 0)
				(type default)
			)
			(fill no)
			(layer "F.CrtYd")
		)
		(fp_line
			(start 0.2794 -0.1016)
			(end -0.2794 -0.1016)
			(stroke
				(width 0.1)
				(type default)
			)
			(layer "F.Fab")
		)
		(fp_line
			(start -0.2794 -0.1016)
			(end -0.2794 0.9906)
			(stroke
				(width 0.1)
				(type default)
			)
			(layer "F.Fab")
		)
		(fp_line
			(start 0.2794 0.9906)
			(end 0.2794 -0.1016)
			(stroke
				(width 0.1)
				(type default)
			)
			(layer "F.Fab")
		)
		(fp_line
			(start -0.2794 0.9906)
			(end 0.2794 0.9906)
			(stroke
				(width 0.1)
				(type default)
			)
			(layer "F.Fab")
		)
		(pad "1" smd rect
			(at 0 0 90)
			(size 0.508 0.508)
			(layers "F.Cu" "F.Mask" "F.Paste")
			(net "VSENSE_PVDDQ_GHJ_P")
		)
		(pad "2" smd rect
			(at 0 0.889 90)
			(size 0.508 0.508)
			(layers "F.Cu" "F.Mask" "F.Paste")
			(net "VR_PVDDQ_GHJ_AVSP")
		)
		(zone
			(layer "F.Cu")
			(hatch none 0.5)
			(connect_pads
				(clearance 0)
			)
			(min_thickness 0.25)
			(keepout
				(tracks allowed)
				(vias not_allowed)
				(pads allowed)
				(copperpour not_allowed)
				(footprints allowed)
			)
			(placement
				(enabled no)
				(sheetname "")
			)
			(fill
				(thermal_gap 0.5)
				(thermal_bridge_width 0.5)
				(island_removal_mode 0)
			)
			(polygon
				(pts
					(xy 7.391146 -4.802886) (xy 7.391146 -4.294886) (xy 7.772146 -4.294886) (xy 7.772146 -4.802886)
				)
			)
		)
		(zone
			(layer "F.Cu")
			(hatch none 0.5)
			(connect_pads
				(clearance 0)
			)
			(min_thickness 0.25)
			(keepout
				(tracks not_allowed)
				(vias allowed)
				(pads allowed)
				(copperpour not_allowed)
				(footprints allowed)
			)
			(placement
				(enabled no)
				(sheetname "")
			)
			(fill
				(thermal_gap 0.5)
				(thermal_bridge_width 0.5)
				(island_removal_mode 0)
			)
			(polygon
				(pts
					(xy 7.391146 -4.802886) (xy 7.391146 -4.294886) (xy 7.772146 -4.294886) (xy 7.772146 -4.802886)
				)
			)
		)
	)
	(footprint ""
		(layer "F.Cu")
		(at 401.8915 -49.403 90)
		(property "Reference" "C7F1"
			(at 0 0 90)
			(layer "F.SilkS")
			(hide yes)
			(effects
				(font
					(size 1.27 1.27)
				)
			)
		)
		(property "Value" ""
			(at 0 0 90)
			(layer "F.Fab")
			(effects
				(font
					(size 1.27 1.27)
				)
			)
		)
		(duplicate_pad_numbers_are_jumpers no)
		(fp_poly
			(pts
				(xy 0.3048 -0.1016) (xy 0.3048 0.9906) (xy -0.3048 0.9906) (xy -0.3048 -0.1016)
			)
			(stroke
				(width 0)
				(type default)
			)
			(fill no)
			(layer "F.CrtYd")
		)
		(fp_line
			(start 0.3048 -0.1016)
			(end -0.3048 -0.1016)
			(stroke
				(width 0.1)
				(type default)
			)
			(layer "F.Fab")
		)
		(fp_line
			(start -0.3048 -0.1016)
			(end -0.3048 0.9906)
			(stroke
				(width 0.1)
				(type default)
			)
			(layer "F.Fab")
		)
		(fp_line
			(start 0.3048 0.9906)
			(end 0.3048 -0.1016)
			(stroke
				(width 0.1)
				(type default)
			)
			(layer "F.Fab")
		)
		(fp_line
			(start -0.3048 0.9906)
			(end 0.3048 0.9906)
			(stroke
				(width 0.1)
				(type default)
			)
			(layer "F.Fab")
		)
		(pad "1" smd rect
			(at 0 0 90)
			(size 0.508 0.508)
			(layers "F.Cu" "F.Mask" "F.Paste")
			(net "P3V3_STBY")
		)
		(pad "2" smd rect
			(at 0 0.889 90)
			(size 0.508 0.508)
			(layers "F.Cu" "F.Mask" "F.Paste")
			(net "GND")
		)
		(zone
			(layer "F.Cu")
			(hatch none 0.5)
			(connect_pads
				(clearance 0)
			)
			(min_thickness 0.25)
			(keepout
				(tracks allowed)
				(vias not_allowed)
				(pads allowed)
				(copperpour not_allowed)
				(footprints allowed)
			)
			(placement
				(enabled no)
				(sheetname "")
			)
			(fill
				(thermal_gap 0.5)
				(thermal_bridge_width 0.5)
				(island_removal_mode 0)
			)
			(polygon
				(pts
					(xy 402.1455 -49.149) (xy 402.1455 -49.657) (xy 402.5265 -49.657) (xy 402.5265 -49.149)
				)
			)
		)
		(zone
			(layer "F.Cu")
			(hatch none 0.5)
			(connect_pads
				(clearance 0)
			)
			(min_thickness 0.25)
			(keepout
				(tracks not_allowed)
				(vias allowed)
				(pads allowed)
				(copperpour not_allowed)
				(footprints allowed)
			)
			(placement
				(enabled no)
				(sheetname "")
			)
			(fill
				(thermal_gap 0.5)
				(thermal_bridge_width 0.5)
				(island_removal_mode 0)
			)
			(polygon
				(pts
					(xy 402.5265 -49.149) (xy 402.5265 -49.657) (xy 402.1455 -49.657) (xy 402.1455 -49.149)
				)
			)
		)
	)
	(footprint ""
		(layer "F.Cu")
		(at 375.539 -132.08 180)
		(property "Reference" "C7B20"
			(at 0 0 180)
			(layer "F.SilkS")
			(hide yes)
			(effects
				(font
					(size 1.27 1.27)
				)
			)
		)
		(property "Value" ""
			(at 0 0 180)
			(layer "F.Fab")
			(effects
				(font
					(size 1.27 1.27)
				)
			)
		)
		(duplicate_pad_numbers_are_jumpers no)
		(fp_poly
			(pts
				(xy -0.4953 -0.2032) (xy 0.4953 -0.2032) (xy 0.4953 1.6002) (xy -0.4953 1.6002)
			)
			(stroke
				(width 0)
				(type default)
			)
			(fill no)
			(layer "F.CrtYd")
		)
		(fp_line
			(start 0.4953 1.6002)
			(end -0.4953 1.6002)
			(stroke
				(width 0.1)
				(type default)
			)
			(layer "F.Fab")
		)
		(fp_line
			(start 0.4953 -0.2032)
			(end 0.4953 1.6002)
			(stroke
				(width 0.1)
				(type default)
			)
			(layer "F.Fab")
		)
		(fp_line
			(start -0.4953 1.6002)
			(end -0.4953 -0.2032)
			(stroke
				(width 0.1)
				(type default)
			)
			(layer "F.Fab")
		)
		(fp_line
			(start -0.4953 -0.2032)
			(end 0.4953 -0.2032)
			(stroke
				(width 0.1)
				(type default)
			)
			(layer "F.Fab")
		)
		(pad "1" smd rect
			(at 0 0 180)
			(size 0.762 0.889)
			(layers "F.Cu" "F.Mask" "F.Paste")
			(net "P1V05_PCH_STBY")
		)
		(pad "2" smd rect
			(at 0 1.397 180)
			(size 0.762 0.889)
			(layers "F.Cu" "F.Mask" "F.Paste")
			(net "GND")
		)
		(zone
			(layer "F.Cu")
			(hatch none 0.5)
			(connect_pads
				(clearance 0)
			)
			(min_thickness 0.25)
			(keepout
				(tracks not_allowed)
				(vias allowed)
				(pads allowed)
				(copperpour not_allowed)
				(footprints allowed)
			)
			(placement
				(enabled no)
				(sheetname "")
			)
			(fill
				(thermal_gap 0.5)
				(thermal_bridge_width 0.5)
				(island_removal_mode 0)
			)
			(polygon
				(pts
					(xy 375.92 -132.5245) (xy 375.158 -132.5245) (xy 375.158 -133.0325) (xy 375.92 -133.0325)
				)
			)
		)
	)
)
